# S9S_MB_2U (Grand Teton) — schematic netlist excerpt (pin names and nets, part order shuffled) for the footprints in the layout excerpt that follows; sources: Cadence DE-HDL packaged netlist, KiCad conversion of 03242023_DA0F0TMBIJ0_F0T_Motherboard_J_brd_V01_OCP.brd

R3710  Q_RES  0 5% CHIP  pkg 0402LF  page 233 : A = RST_SMB_SWITCH_N ; B = PU_RST_SMB_PCIE2_N
H38  HOLE  EMPTY  pkg TH  page 311 : \1\ = NC

(kicad_pcb
	(version 20260206)
	(generator "pcbnew")
	(generator_version "10.0")
	(general
		(thickness 1.6)
		(legacy_teardrops no)
	)
	(paper "A4")
	(title_block
		(title "03242023_DA0F0TMBIJ0_F0T_Motherboard_J_brd_V01_OCP.brd")
		(comment 1 "Grand Teton / footprints 2689-2690 of 6105")
	)
	(layers
		(0 "F.Cu" signal "TOP")
		(4 "In1.Cu" signal "GND")
		(6 "In2.Cu" signal "IN1")
		(8 "In3.Cu" signal "GND1")
		(10 "In4.Cu" signal "IN2")
		(12 "In5.Cu" signal "GND2")
		(14 "In6.Cu" signal "IN3")
		(16 "In7.Cu" signal "GND3")
		(18 "In8.Cu" signal "VCC")
		(20 "In9.Cu" signal "VCC1")
		(22 "In10.Cu" signal "GND4")
		(24 "In11.Cu" signal "IN4")
		(26 "In12.Cu" signal "GND5")
		(28 "In13.Cu" signal "IN5")
		(30 "In14.Cu" signal "GND6")
		(32 "In15.Cu" signal "IN6")
		(34 "In16.Cu" signal "GND7")
		(2 "B.Cu" signal "BOTTOM")
		(9 "F.Adhes" user "F.Adhesive")
		(11 "B.Adhes" user "B.Adhesive")
		(13 "F.Paste" user "Package Geometry/Pastemask Top")
		(15 "B.Paste" user "Package Geometry/Pastemask Bottom")
		(5 "F.SilkS" user "Ref Des/Silkscreen Top")
		(7 "B.SilkS" user "Ref Des/Silkscreen Bottom")
		(1 "F.Mask" user "Board Geometry/Soldermask Top")
		(3 "B.Mask" user "Board Geometry/Soldermask Bottom")
		(17 "Dwgs.User" user "User.Drawings")
		(19 "Cmts.User" user "User.Comments")
		(21 "Eco1.User" user "User.Eco1")
		(23 "Eco2.User" user "User.Eco2")
		(25 "Edge.Cuts" user "Board Geometry/Outline")
		(27 "Margin" user)
		(31 "F.CrtYd" user "Package Geometry/Place Bound Top")
		(29 "B.CrtYd" user "Package Geometry/Place Bound Bottom")
		(35 "F.Fab" user "Ref Des/Assembly Top")
		(33 "B.Fab" user "Ref Des/Assembly Bottom")
	)
	(footprint ""
		(layer "F.Cu")
		(at 54.242716 -114.99469)
		(property "Reference" "R3710"
			(at 0 0 0)
			(layer "F.SilkS")
			(hide yes)
			(effects
				(font
					(size 1.27 1.27)
				)
			)
		)
		(property "Value" ""
			(at 0 0 0)
			(layer "F.Fab")
			(effects
				(font
					(size 1.27 1.27)
				)
			)
		)
		(duplicate_pad_numbers_are_jumpers no)
		(fp_line
			(start -0.7874 -0.4064)
			(end 0.7874 -0.4064)
			(stroke
				(width 0.1524)
				(type default)
			)
			(layer "F.SilkS")
		)
		(fp_line
			(start -0.7874 0.4064)
			(end -0.7874 -0.4064)
			(stroke
				(width 0.1524)
				(type default)
			)
			(layer "F.SilkS")
		)
		(fp_line
			(start 0.7874 -0.4064)
			(end 0.7874 0.4064)
			(stroke
				(width 0.1524)
				(type default)
			)
			(layer "F.SilkS")
		)
		(fp_line
			(start 0.7874 0.4064)
			(end -0.7874 0.4064)
			(stroke
				(width 0.1524)
				(type default)
			)
			(layer "F.SilkS")
		)
		(fp_line
			(start -0.67945 -0.305054)
			(end -0.12065 -0.305054)
			(stroke
				(width 0.1)
				(type default)
			)
			(layer "F.Fab")
		)
		(fp_line
			(start -0.67945 0.3048)
			(end -0.67945 -0.305054)
			(stroke
				(width 0.1)
				(type default)
			)
			(layer "F.Fab")
		)
		(fp_line
			(start -0.12065 -0.305054)
			(end -0.12065 -0.2794)
			(stroke
				(width 0.1)
				(type default)
			)
			(layer "F.Fab")
		)
		(fp_line
			(start -0.12065 -0.2794)
			(end 0.12065 -0.2794)
			(stroke
				(width 0.1)
				(type default)
			)
			(layer "F.Fab")
		)
		(fp_line
			(start -0.12065 0.2794)
			(end -0.12065 0.3048)
			(stroke
				(width 0.1)
				(type default)
			)
			(layer "F.Fab")
		)
		(fp_line
			(start -0.12065 0.3048)
			(end -0.67945 0.3048)
			(stroke
				(width 0.1)
				(type default)
			)
			(layer "F.Fab")
		)
		(fp_line
			(start 0.120396 0.2794)
			(end -0.12065 0.2794)
			(stroke
				(width 0.1)
				(type default)
			)
			(layer "F.Fab")
		)
		(fp_line
			(start 0.120396 0.3048)
			(end 0.120396 0.2794)
			(stroke
				(width 0.1)
				(type default)
			)
			(layer "F.Fab")
		)
		(fp_line
			(start 0.12065 -0.3048)
			(end 0.67945 -0.3048)
			(stroke
				(width 0.1)
				(type default)
			)
			(layer "F.Fab")
		)
		(fp_line
			(start 0.12065 -0.2794)
			(end 0.12065 -0.3048)
			(stroke
				(width 0.1)
				(type default)
			)
			(layer "F.Fab")
		)
		(fp_line
			(start 0.67945 -0.3048)
			(end 0.67945 0.3048)
			(stroke
				(width 0.1)
				(type default)
			)
			(layer "F.Fab")
		)
		(fp_line
			(start 0.67945 0.3048)
			(end 0.120396 0.3048)
			(stroke
				(width 0.1)
				(type default)
			)
			(layer "F.Fab")
		)
		(pad "1" smd circle
			(at -0.40005 0)
			(size 0 0)
			(layers "F.Cu" "F.Mask" "F.Paste")
			(net "RST_SMB_SWITCH_N")
		)
		(pad "2" smd circle
			(at 0.40005 0)
			(size 0 0)
			(layers "F.Cu" "F.Mask" "F.Paste")
			(net "PU_RST_SMB_PCIE2_N")
		)
	)
	(footprint ""
		(layer "F.Cu")
		(at 316.900052 -68.449952)
		(property "Reference" "H38"
			(at -3.30454 -3.96621 0)
			(unlocked yes)
			(layer "F.SilkS")
			(effects
				(font
					(size 0.7874 0.5842)
					(thickness 0.1524)
				)
				(justify left)
			)
		)
		(property "Value" ""
			(at 0 0 0)
			(layer "F.Fab")
			(effects
				(font
					(size 1.27 1.27)
				)
			)
		)
		(duplicate_pad_numbers_are_jumpers no)
		(fp_circle
			(center 0 0)
			(end 2.3622 0)
			(stroke
				(width 0.1524)
				(type default)
			)
			(fill no)
			(layer "F.SilkS")
		)
		(fp_circle
			(center 0 0)
			(end 2.3622 0)
			(stroke
				(width 0.1524)
				(type default)
			)
			(fill no)
			(layer "B.SilkS")
		)
		(fp_circle
			(center 0 0)
			(end 2.3622 0)
			(stroke
				(width 0.1)
				(type default)
			)
			(fill no)
			(layer "B.Fab")
		)
		(fp_circle
			(center 0 0)
			(end 2.3622 0)
			(stroke
				(width 0.1)
				(type default)
			)
			(fill no)
			(layer "F.Fab")
		)
		(pad "" np_thru_hole circle
			(at 0 0)
			(size 3.0988 3.0988)
			(drill 3.0988)
			(layers "*.Cu" "*.Mask")
			(clearance 0.254)
			(thermal_gap 0.254)
		)
	)
)
